(kicad_pcb
	(version 20260206)
	(generator "pcbnew")
	(generator_version "10.0")
	(general
		(thickness 1.6)
		(legacy_teardrops no)
	)
	(paper "A4")
	(title_block
		(title "04192023_DAF0TMB3IC0_F0TG_MB_C_brd_V02_OCP.brd")
		(comment 1 "Grand Teton / footprints 5731-5738 of 8354")
	)
	(layers
		(0 "F.Cu" signal "TOP")
		(4 "In1.Cu" signal "GND")
		(6 "In2.Cu" signal "IN1")
		(8 "In3.Cu" signal "GND1")
		(10 "In4.Cu" signal "IN2")
		(12 "In5.Cu" signal "GND2")
		(14 "In6.Cu" signal "IN3")
		(16 "In7.Cu" signal "GND3")
		(18 "In8.Cu" signal "VCC")
		(20 "In9.Cu" signal "VCC1")
		(22 "In10.Cu" signal "GND4")
		(24 "In11.Cu" signal "IN4")
		(26 "In12.Cu" signal "GND5")
		(28 "In13.Cu" signal "IN5")
		(30 "In14.Cu" signal "GND6")
		(32 "In15.Cu" signal "IN6")
		(34 "In16.Cu" signal "GND7")
		(2 "B.Cu" signal "BOTTOM")
		(9 "F.Adhes" user "F.Adhesive")
		(11 "B.Adhes" user "B.Adhesive")
		(13 "F.Paste" user "Package Geometry/Pastemask Top")
		(15 "B.Paste" user "Package Geometry/Pastemask Bottom")
		(5 "F.SilkS" user "Ref Des/Silkscreen Top")
		(7 "B.SilkS" user "Ref Des/Silkscreen Bottom")
		(1 "F.Mask" user "Board Geometry/Soldermask Top")
		(3 "B.Mask" user "Board Geometry/Soldermask Bottom")
		(17 "Dwgs.User" user "User.Drawings")
		(19 "Cmts.User" user "User.Comments")
		(21 "Eco1.User" user "User.Eco1")
		(23 "Eco2.User" user "User.Eco2")
		(25 "Edge.Cuts" user "Board Geometry/Outline")
		(27 "Margin" user)
		(31 "F.CrtYd" user "Package Geometry/Place Bound Top")
		(29 "B.CrtYd" user "Package Geometry/Place Bound Bottom")
		(35 "F.Fab" user "Ref Des/Assembly Top")
		(33 "B.Fab" user "Ref Des/Assembly Bottom")
	)
	(footprint ""
		(layer "B.Cu")
		(at 234.4801 -226.822 180)
		(property "Reference" "R140"
			(at 0 0 0)
			(layer "B.SilkS")
			(hide yes)
			(effects
				(font
					(size 1.27 1.27)
				)
				(justify mirror)
			)
		)
		(property "Value" ""
			(at 0 0 0)
			(layer "B.Fab")
			(effects
				(font
					(size 1.27 1.27)
				)
				(justify mirror)
			)
		)
		(duplicate_pad_numbers_are_jumpers no)
		(fp_line
			(start 0.7874 0.4064)
			(end 0.7874 -0.4064)
			(stroke
				(width 0.1524)
				(type default)
			)
			(layer "B.SilkS")
		)
		(fp_line
			(start 0.7874 -0.4064)
			(end -0.7874 -0.4064)
			(stroke
				(width 0.1524)
				(type default)
			)
			(layer "B.SilkS")
		)
		(fp_line
			(start -0.7874 0.4064)
			(end 0.7874 0.4064)
			(stroke
				(width 0.1524)
				(type default)
			)
			(layer "B.SilkS")
		)
		(fp_line
			(start -0.7874 -0.4064)
			(end -0.7874 0.4064)
			(stroke
				(width 0.1524)
				(type default)
			)
			(layer "B.SilkS")
		)
		(fp_line
			(start 0.67945 0.3048)
			(end 0.67945 -0.305054)
			(stroke
				(width 0.1)
				(type default)
			)
			(layer "B.Fab")
		)
		(fp_line
			(start 0.67945 -0.305054)
			(end 0.12065 -0.305054)
			(stroke
				(width 0.1)
				(type default)
			)
			(layer "B.Fab")
		)
		(fp_line
			(start 0.12065 0.3048)
			(end 0.67945 0.3048)
			(stroke
				(width 0.1)
				(type default)
			)
			(layer "B.Fab")
		)
		(fp_line
			(start 0.12065 0.2794)
			(end 0.12065 0.3048)
			(stroke
				(width 0.1)
				(type default)
			)
			(layer "B.Fab")
		)
		(fp_line
			(start 0.12065 -0.2794)
			(end -0.12065 -0.2794)
			(stroke
				(width 0.1)
				(type default)
			)
			(layer "B.Fab")
		)
		(fp_line
			(start 0.12065 -0.305054)
			(end 0.12065 -0.2794)
			(stroke
				(width 0.1)
				(type default)
			)
			(layer "B.Fab")
		)
		(fp_line
			(start -0.120396 0.3048)
			(end -0.120396 0.2794)
			(stroke
				(width 0.1)
				(type default)
			)
			(layer "B.Fab")
		)
		(fp_line
			(start -0.120396 0.2794)
			(end 0.12065 0.2794)
			(stroke
				(width 0.1)
				(type default)
			)
			(layer "B.Fab")
		)
		(fp_line
			(start -0.12065 -0.2794)
			(end -0.12065 -0.3048)
			(stroke
				(width 0.1)
				(type default)
			)
			(layer "B.Fab")
		)
		(fp_line
			(start -0.12065 -0.3048)
			(end -0.67945 -0.3048)
			(stroke
				(width 0.1)
				(type default)
			)
			(layer "B.Fab")
		)
		(fp_line
			(start -0.67945 0.3048)
			(end -0.120396 0.3048)
			(stroke
				(width 0.1)
				(type default)
			)
			(layer "B.Fab")
		)
		(fp_line
			(start -0.67945 -0.3048)
			(end -0.67945 0.3048)
			(stroke
				(width 0.1)
				(type default)
			)
			(layer "B.Fab")
		)
		(pad "1" smd rect
			(at 0.40005 0 180)
			(size 0.4572 0.508)
			(layers "B.Cu" "B.Mask" "B.Paste")
			(net "SMB_CPU0_CPU1_APML_SCL")
		)
		(pad "2" smd rect
			(at -0.40005 0 180)
			(size 0.4572 0.508)
			(layers "B.Cu" "B.Mask" "B.Paste")
			(net "SMB_CPU0_CPU1_APML_BUF1_SCL")
		)
	)
	(footprint ""
		(layer "B.Cu")
		(at 45.099986 -388.609078 90)
		(property "Reference" "C281"
			(at 0 0 90)
			(layer "B.SilkS")
			(hide yes)
			(effects
				(font
					(size 1.27 1.27)
				)
				(justify mirror)
			)
		)
		(property "Value" ""
			(at 0 0 90)
			(layer "B.Fab")
			(effects
				(font
					(size 1.27 1.27)
				)
				(justify mirror)
			)
		)
		(duplicate_pad_numbers_are_jumpers no)
		(fp_line
			(start 0.299974 -0.150114)
			(end -0.299974 -0.150114)
			(stroke
				(width 0.1)
				(type default)
			)
			(layer "B.Fab")
		)
		(fp_line
			(start -0.299974 -0.150114)
			(end -0.299974 0.150114)
			(stroke
				(width 0.1)
				(type default)
			)
			(layer "B.Fab")
		)
		(fp_line
			(start 0.299974 0.150114)
			(end 0.299974 -0.150114)
			(stroke
				(width 0.1)
				(type default)
			)
			(layer "B.Fab")
		)
		(fp_line
			(start -0.299974 0.150114)
			(end 0.299974 0.150114)
			(stroke
				(width 0.1)
				(type default)
			)
			(layer "B.Fab")
		)
		(pad "1" smd rect
			(at 0.2667 0 270)
			(size 0.3048 0.381)
			(layers "B.Cu" "B.Mask" "B.Paste")
			(net "P0V9_CPU1_RT0_2A")
		)
		(pad "2" smd rect
			(at -0.2667 0 270)
			(size 0.3048 0.381)
			(layers "B.Cu" "B.Mask" "B.Paste")
			(net "GND")
		)
	)
	(footprint ""
		(layer "B.Cu")
		(at 366.36579 -393.04468 180)
		(property "Reference" "R1118"
			(at 0 0 0)
			(layer "B.SilkS")
			(hide yes)
			(effects
				(font
					(size 1.27 1.27)
				)
				(justify mirror)
			)
		)
		(property "Value" ""
			(at 0 0 0)
			(layer "B.Fab")
			(effects
				(font
					(size 1.27 1.27)
				)
				(justify mirror)
			)
		)
		(duplicate_pad_numbers_are_jumpers no)
		(fp_line
			(start 0.32512 0.175006)
			(end 0.32512 -0.175006)
			(stroke
				(width 0.1)
				(type default)
			)
			(layer "B.Fab")
		)
		(fp_line
			(start 0.32512 -0.175006)
			(end -0.32512 -0.175006)
			(stroke
				(width 0.1)
				(type default)
			)
			(layer "B.Fab")
		)
		(fp_line
			(start -0.32512 0.175006)
			(end 0.32512 0.175006)
			(stroke
				(width 0.1)
				(type default)
			)
			(layer "B.Fab")
		)
		(fp_line
			(start -0.32512 -0.175006)
			(end -0.32512 0.175006)
			(stroke
				(width 0.1)
				(type default)
			)
			(layer "B.Fab")
		)
		(pad "1" smd rect
			(at 0.2667 0)
			(size 0.3048 0.381)
			(layers "B.Cu" "B.Mask" "B.Paste")
			(net "TEST1_RT_CPU0_P3")
		)
		(pad "2" smd rect
			(at -0.2667 0 180)
			(size 0.3048 0.381)
			(layers "B.Cu" "B.Mask" "B.Paste")
			(net "GND")
		)
	)
	(footprint ""
		(layer "B.Cu")
		(at 273.847814 -193.99631)
		(property "Reference" "R93"
			(at 0 0 0)
			(layer "B.SilkS")
			(hide yes)
			(effects
				(font
					(size 1.27 1.27)
				)
				(justify mirror)
			)
		)
		(property "Value" ""
			(at 0 0 0)
			(layer "B.Fab")
			(effects
				(font
					(size 1.27 1.27)
				)
				(justify mirror)
			)
		)
		(duplicate_pad_numbers_are_jumpers no)
		(fp_line
			(start -0.7874 -0.4064)
			(end -0.7874 0.4064)
			(stroke
				(width 0.1524)
				(type default)
			)
			(layer "B.SilkS")
		)
		(fp_line
			(start -0.7874 0.4064)
			(end 0.7874 0.4064)
			(stroke
				(width 0.1524)
				(type default)
			)
			(layer "B.SilkS")
		)
		(fp_line
			(start 0.7874 -0.4064)
			(end -0.7874 -0.4064)
			(stroke
				(width 0.1524)
				(type default)
			)
			(layer "B.SilkS")
		)
		(fp_line
			(start 0.7874 0.4064)
			(end 0.7874 -0.4064)
			(stroke
				(width 0.1524)
				(type default)
			)
			(layer "B.SilkS")
		)
		(fp_line
			(start -0.67945 -0.3048)
			(end -0.67945 0.3048)
			(stroke
				(width 0.1)
				(type default)
			)
			(layer "B.Fab")
		)
		(fp_line
			(start -0.67945 0.3048)
			(end -0.120396 0.3048)
			(stroke
				(width 0.1)
				(type default)
			)
			(layer "B.Fab")
		)
		(fp_line
			(start -0.12065 -0.3048)
			(end -0.67945 -0.3048)
			(stroke
				(width 0.1)
				(type default)
			)
			(layer "B.Fab")
		)
		(fp_line
			(start -0.12065 -0.2794)
			(end -0.12065 -0.3048)
			(stroke
				(width 0.1)
				(type default)
			)
			(layer "B.Fab")
		)
		(fp_line
			(start -0.120396 0.2794)
			(end 0.12065 0.2794)
			(stroke
				(width 0.1)
				(type default)
			)
			(layer "B.Fab")
		)
		(fp_line
			(start -0.120396 0.3048)
			(end -0.120396 0.2794)
			(stroke
				(width 0.1)
				(type default)
			)
			(layer "B.Fab")
		)
		(fp_line
			(start 0.12065 -0.305054)
			(end 0.12065 -0.2794)
			(stroke
				(width 0.1)
				(type default)
			)
			(layer "B.Fab")
		)
		(fp_line
			(start 0.12065 -0.2794)
			(end -0.12065 -0.2794)
			(stroke
				(width 0.1)
				(type default)
			)
			(layer "B.Fab")
		)
		(fp_line
			(start 0.12065 0.2794)
			(end 0.12065 0.3048)
			(stroke
				(width 0.1)
				(type default)
			)
			(layer "B.Fab")
		)
		(fp_line
			(start 0.12065 0.3048)
			(end 0.67945 0.3048)
			(stroke
				(width 0.1)
				(type default)
			)
			(layer "B.Fab")
		)
		(fp_line
			(start 0.67945 -0.305054)
			(end 0.12065 -0.305054)
			(stroke
				(width 0.1)
				(type default)
			)
			(layer "B.Fab")
		)
		(fp_line
			(start 0.67945 0.3048)
			(end 0.67945 -0.305054)
			(stroke
				(width 0.1)
				(type default)
			)
			(layer "B.Fab")
		)
		(pad "1" smd circle
			(at 0.40005 0 180)
			(size 0 0)
			(layers "B.Cu" "B.Mask" "B.Paste")
			(net "P3V3")
		)
		(pad "2" smd circle
			(at -0.40005 0 180)
			(size 0 0)
			(layers "B.Cu" "B.Mask" "B.Paste")
			(net "PWRGD_CHE_CPU0_DIMM")
		)
	)
	(footprint ""
		(layer "B.Cu")
		(at 371.134386 -214.523828 90)
		(property "Reference" "R4536"
			(at 0 0 90)
			(layer "B.SilkS")
			(hide yes)
			(effects
				(font
					(size 1.27 1.27)
				)
				(justify mirror)
			)
		)
		(property "Value" ""
			(at 0 0 90)
			(layer "B.Fab")
			(effects
				(font
					(size 1.27 1.27)
				)
				(justify mirror)
			)
		)
		(duplicate_pad_numbers_are_jumpers no)
		(fp_line
			(start 0.7874 -0.4064)
			(end -0.7874 -0.4064)
			(stroke
				(width 0.1524)
				(type default)
			)
			(layer "B.SilkS")
		)
		(fp_line
			(start -0.7874 -0.4064)
			(end -0.7874 -0.014986)
			(stroke
				(width 0.1524)
				(type default)
			)
			(layer "B.SilkS")
		)
		(fp_line
			(start 0.7874 -0.040386)
			(end 0.7874 -0.4064)
			(stroke
				(width 0.1524)
				(type default)
			)
			(layer "B.SilkS")
		)
		(fp_line
			(start -0.351028 0.4064)
			(end 0.512572 0.4064)
			(stroke
				(width 0.1524)
				(type default)
			)
			(layer "B.SilkS")
		)
		(fp_line
			(start 0.67945 -0.305054)
			(end 0.12065 -0.305054)
			(stroke
				(width 0.1)
				(type default)
			)
			(layer "B.Fab")
		)
		(fp_line
			(start 0.12065 -0.305054)
			(end 0.12065 -0.2794)
			(stroke
				(width 0.1)
				(type default)
			)
			(layer "B.Fab")
		)
		(fp_line
			(start -0.12065 -0.3048)
			(end -0.67945 -0.3048)
			(stroke
				(width 0.1)
				(type default)
			)
			(layer "B.Fab")
		)
		(fp_line
			(start -0.67945 -0.3048)
			(end -0.67945 0.3048)
			(stroke
				(width 0.1)
				(type default)
			)
			(layer "B.Fab")
		)
		(fp_line
			(start 0.12065 -0.2794)
			(end -0.12065 -0.2794)
			(stroke
				(width 0.1)
				(type default)
			)
			(layer "B.Fab")
		)
		(fp_line
			(start -0.12065 -0.2794)
			(end -0.12065 -0.3048)
			(stroke
				(width 0.1)
				(type default)
			)
			(layer "B.Fab")
		)
		(fp_line
			(start 0.12065 0.2794)
			(end 0.12065 0.3048)
			(stroke
				(width 0.1)
				(type default)
			)
			(layer "B.Fab")
		)
		(fp_line
			(start -0.120396 0.2794)
			(end 0.12065 0.2794)
			(stroke
				(width 0.1)
				(type default)
			)
			(layer "B.Fab")
		)
		(fp_line
			(start 0.67945 0.3048)
			(end 0.67945 -0.305054)
			(stroke
				(width 0.1)
				(type default)
			)
			(layer "B.Fab")
		)
		(fp_line
			(start 0.12065 0.3048)
			(end 0.67945 0.3048)
			(stroke
				(width 0.1)
				(type default)
			)
			(layer "B.Fab")
		)
		(fp_line
			(start -0.120396 0.3048)
			(end -0.120396 0.2794)
			(stroke
				(width 0.1)
				(type default)
			)
			(layer "B.Fab")
		)
		(fp_line
			(start -0.67945 0.3048)
			(end -0.120396 0.3048)
			(stroke
				(width 0.1)
				(type default)
			)
			(layer "B.Fab")
		)
		(pad "1" smd circle
			(at 0.40005 0 270)
			(size 0 0)
			(layers "B.Cu" "B.Mask" "B.Paste")
			(net "CLK_100M_CPU0_CLK01_R_DN")
		)
		(pad "2" smd circle
			(at -0.40005 0 270)
			(size 0 0)
			(layers "B.Cu" "B.Mask" "B.Paste")
			(net "CLK_100M_CPU0_CLK01_DN")
		)
	)
	(footprint ""
		(layer "B.Cu")
		(at 115.678458 -386.766562 90)
		(property "Reference" "C491"
			(at 0 0 90)
			(layer "B.SilkS")
			(hide yes)
			(effects
				(font
					(size 1.27 1.27)
				)
				(justify mirror)
			)
		)
		(property "Value" ""
			(at 0 0 90)
			(layer "B.Fab")
			(effects
				(font
					(size 1.27 1.27)
				)
				(justify mirror)
			)
		)
		(duplicate_pad_numbers_are_jumpers no)
		(fp_line
			(start 0.299974 -0.150114)
			(end -0.299974 -0.150114)
			(stroke
				(width 0.1)
				(type default)
			)
			(layer "B.Fab")
		)
		(fp_line
			(start -0.299974 -0.150114)
			(end -0.299974 0.150114)
			(stroke
				(width 0.1)
				(type default)
			)
			(layer "B.Fab")
		)
		(fp_line
			(start 0.299974 0.150114)
			(end 0.299974 -0.150114)
			(stroke
				(width 0.1)
				(type default)
			)
			(layer "B.Fab")
		)
		(fp_line
			(start -0.299974 0.150114)
			(end 0.299974 0.150114)
			(stroke
				(width 0.1)
				(type default)
			)
			(layer "B.Fab")
		)
		(pad "1" smd rect
			(at 0.2667 0 270)
			(size 0.3048 0.381)
			(layers "B.Cu" "B.Mask" "B.Paste")
			(net "P0V9_CPU1_RT3_2A")
		)
		(pad "2" smd rect
			(at -0.2667 0 270)
			(size 0.3048 0.381)
			(layers "B.Cu" "B.Mask" "B.Paste")
			(net "GND")
		)
	)
	(footprint ""
		(layer "B.Cu")
		(at 397.830802 -314.366148 180)
		(property "Reference" "C214"
			(at 0 0 0)
			(layer "B.SilkS")
			(hide yes)
			(effects
				(font
					(size 1.27 1.27)
				)
				(justify mirror)
			)
		)
		(property "Value" ""
			(at 0 0 0)
			(layer "B.Fab")
			(effects
				(font
					(size 1.27 1.27)
				)
				(justify mirror)
			)
		)
		(duplicate_pad_numbers_are_jumpers no)
		(fp_line
			(start 0.7874 0.4064)
			(end 0.7874 -0.4064)
			(stroke
				(width 0.1524)
				(type default)
			)
			(layer "B.SilkS")
		)
		(fp_line
			(start 0.7874 -0.4064)
			(end -0.7874 -0.4064)
			(stroke
				(width 0.1524)
				(type default)
			)
			(layer "B.SilkS")
		)
		(fp_line
			(start -0.7874 0.4064)
			(end 0.7874 0.4064)
			(stroke
				(width 0.1524)
				(type default)
			)
			(layer "B.SilkS")
		)
		(fp_line
			(start -0.7874 -0.4064)
			(end -0.7874 0.4064)
			(stroke
				(width 0.1524)
				(type default)
			)
			(layer "B.SilkS")
		)
		(fp_line
			(start 0.67945 0.3048)
			(end 0.67945 -0.305054)
			(stroke
				(width 0.1)
				(type default)
			)
			(layer "B.Fab")
		)
		(fp_line
			(start 0.67945 -0.305054)
			(end 0.12065 -0.305054)
			(stroke
				(width 0.1)
				(type default)
			)
			(layer "B.Fab")
		)
		(fp_line
			(start 0.12065 0.3048)
			(end 0.67945 0.3048)
			(stroke
				(width 0.1)
				(type default)
			)
			(layer "B.Fab")
		)
		(fp_line
			(start 0.12065 0.2794)
			(end 0.12065 0.3048)
			(stroke
				(width 0.1)
				(type default)
			)
			(layer "B.Fab")
		)
		(fp_line
			(start 0.12065 -0.2794)
			(end -0.12065 -0.2794)
			(stroke
				(width 0.1)
				(type default)
			)
			(layer "B.Fab")
		)
		(fp_line
			(start 0.12065 -0.305054)
			(end 0.12065 -0.2794)
			(stroke
				(width 0.1)
				(type default)
			)
			(layer "B.Fab")
		)
		(fp_line
			(start -0.120396 0.3048)
			(end -0.120396 0.2794)
			(stroke
				(width 0.1)
				(type default)
			)
			(layer "B.Fab")
		)
		(fp_line
			(start -0.120396 0.2794)
			(end 0.12065 0.2794)
			(stroke
				(width 0.1)
				(type default)
			)
			(layer "B.Fab")
		)
		(fp_line
			(start -0.12065 -0.2794)
			(end -0.12065 -0.3048)
			(stroke
				(width 0.1)
				(type default)
			)
			(layer "B.Fab")
		)
		(fp_line
			(start -0.12065 -0.3048)
			(end -0.67945 -0.3048)
			(stroke
				(width 0.1)
				(type default)
			)
			(layer "B.Fab")
		)
		(fp_line
			(start -0.67945 0.3048)
			(end -0.120396 0.3048)
			(stroke
				(width 0.1)
				(type default)
			)
			(layer "B.Fab")
		)
		(fp_line
			(start -0.67945 -0.3048)
			(end -0.67945 0.3048)
			(stroke
				(width 0.1)
				(type default)
			)
			(layer "B.Fab")
		)
		(pad "1" smd circle
			(at 0.40005 0)
			(size 0 0)
			(layers "B.Cu" "B.Mask" "B.Paste")
			(net "XTAL_CPU0_X48M_X2_R")
		)
		(pad "2" smd circle
			(at -0.40005 0)
			(size 0 0)
			(layers "B.Cu" "B.Mask" "B.Paste")
			(net "GND")
		)
	)
	(footprint ""
		(layer "B.Cu")
		(at 445.647318 -244.08511)
		(property "Reference" "R385"
			(at 0 0 0)
			(layer "B.SilkS")
			(hide yes)
			(effects
				(font
					(size 1.27 1.27)
				)
				(justify mirror)
			)
		)
		(property "Value" ""
			(at 0 0 0)
			(layer "B.Fab")
			(effects
				(font
					(size 1.27 1.27)
				)
				(justify mirror)
			)
		)
		(duplicate_pad_numbers_are_jumpers no)
		(fp_line
			(start -0.7874 -0.4064)
			(end -0.7874 0.4064)
			(stroke
				(width 0.1524)
				(type default)
			)
			(layer "B.SilkS")
		)
		(fp_line
			(start -0.7874 0.4064)
			(end 0.7874 0.4064)
			(stroke
				(width 0.1524)
				(type default)
			)
			(layer "B.SilkS")
		)
		(fp_line
			(start 0.7874 -0.4064)
			(end -0.7874 -0.4064)
			(stroke
				(width 0.1524)
				(type default)
			)
			(layer "B.SilkS")
		)
		(fp_line
			(start 0.7874 0.4064)
			(end 0.7874 -0.4064)
			(stroke
				(width 0.1524)
				(type default)
			)
			(layer "B.SilkS")
		)
		(fp_line
			(start -0.67945 -0.3048)
			(end -0.67945 0.3048)
			(stroke
				(width 0.1)
				(type default)
			)
			(layer "B.Fab")
		)
		(fp_line
			(start -0.67945 0.3048)
			(end -0.120396 0.3048)
			(stroke
				(width 0.1)
				(type default)
			)
			(layer "B.Fab")
		)
		(fp_line
			(start -0.12065 -0.3048)
			(end -0.67945 -0.3048)
			(stroke
				(width 0.1)
				(type default)
			)
			(layer "B.Fab")
		)
		(fp_line
			(start -0.12065 -0.2794)
			(end -0.12065 -0.3048)
			(stroke
				(width 0.1)
				(type default)
			)
			(layer "B.Fab")
		)
		(fp_line
			(start -0.120396 0.2794)
			(end 0.12065 0.2794)
			(stroke
				(width 0.1)
				(type default)
			)
			(layer "B.Fab")
		)
		(fp_line
			(start -0.120396 0.3048)
			(end -0.120396 0.2794)
			(stroke
				(width 0.1)
				(type default)
			)
			(layer "B.Fab")
		)
		(fp_line
			(start 0.12065 -0.305054)
			(end 0.12065 -0.2794)
			(stroke
				(width 0.1)
				(type default)
			)
			(layer "B.Fab")
		)
		(fp_line
			(start 0.12065 -0.2794)
			(end -0.12065 -0.2794)
			(stroke
				(width 0.1)
				(type default)
			)
			(layer "B.Fab")
		)
		(fp_line
			(start 0.12065 0.2794)
			(end 0.12065 0.3048)
			(stroke
				(width 0.1)
				(type default)
			)
			(layer "B.Fab")
		)
		(fp_line
			(start 0.12065 0.3048)
			(end 0.67945 0.3048)
			(stroke
				(width 0.1)
				(type default)
			)
			(layer "B.Fab")
		)
		(fp_line
			(start 0.67945 -0.305054)
			(end 0.12065 -0.305054)
			(stroke
				(width 0.1)
				(type default)
			)
			(layer "B.Fab")
		)
		(fp_line
			(start 0.67945 0.3048)
			(end 0.67945 -0.305054)
			(stroke
				(width 0.1)
				(type default)
			)
			(layer "B.Fab")
		)
		(pad "1" smd circle
			(at 0.40005 0 180)
			(size 0 0)
			(layers "B.Cu" "B.Mask" "B.Paste")
			(net "M_K_CPU0_ALERT_N")
		)
		(pad "2" smd circle
			(at -0.40005 0 180)
			(size 0 0)
			(layers "B.Cu" "B.Mask" "B.Paste")
			(net "M_K_CPU0_ALERT_R_N")
		)
	)
)
